FILE_TYPE = CONNECTIVITY;
{Allegro Design Entry HDL 17.2-2016 S081 (4005846) 1/11/2022}
"PAGE_NUMBER" = 25;
0"NC";
1"M_F_CPU0_SA_CA<6:0>";
2"M_F_CPU0_SA_CS_N<3:0>";
3"M_F_CPU0_SA_DQS_DN<9:0>";
4"M_F_CPU0_SA_DQS_DP<9:0>";
5"M_F_CPU0_SB_CA<6:0>";
6"M_F_CPU0_SB_CS_N<3:0>";
7"M_F_CPU0_SB_DQS_DN<9:0>";
8"M_F_CPU0_SB_DQS_DP<9:0>";
9"M_F_CPU0_SB_CB<7:0>";
10"M_F_CPU0_SB_DQ<31:0>";
11"M_F_CPU0_SA_CB<7:0>";
12"M_F_CPU0_SA_DQ<31:0>";
13"M_F_CPU0_CLK_DP<1:0>";
14"M_F_CPU0_CLK_DN<1:0>";
15"M_F_CPU0_CLK_DN<1>";
16"M_F_CPU0_CLK_DN<0>";
17"M_F_CPU0_CLK_DP<1>";
18"M_F_CPU0_CLK_DP<0>";
19"M_F_CPU0_SA_DQ<31>";
20"M_F_CPU0_SA_DQ<30>";
21"M_F_CPU0_SA_DQ<29>";
22"M_F_CPU0_SA_DQ<28>";
23"M_F_CPU0_SA_DQ<27>";
24"M_F_CPU0_SA_DQ<26>";
25"M_F_CPU0_SA_DQ<25>";
26"M_F_CPU0_SA_DQ<24>";
27"M_F_CPU0_SA_DQ<23>";
28"M_F_CPU0_SA_DQ<22>";
29"M_F_CPU0_SA_DQ<21>";
30"M_F_CPU0_SA_DQ<20>";
31"M_F_CPU0_SA_DQ<19>";
32"M_F_CPU0_SA_DQ<18>";
33"M_F_CPU0_SA_DQ<17>";
34"M_F_CPU0_SA_DQ<16>";
35"M_F_CPU0_SA_DQ<15>";
36"M_F_CPU0_SA_DQ<14>";
37"M_F_CPU0_SA_DQ<13>";
38"M_F_CPU0_SA_DQ<12>";
39"M_F_CPU0_SA_DQ<11>";
40"M_F_CPU0_SA_DQ<10>";
41"M_F_CPU0_SA_DQ<9>";
42"M_F_CPU0_SA_DQ<8>";
43"M_F_CPU0_SA_DQ<7>";
44"M_F_CPU0_SA_DQ<6>";
45"M_F_CPU0_SA_DQ<5>";
46"M_F_CPU0_SA_DQ<4>";
47"M_F_CPU0_SA_DQ<3>";
48"M_F_CPU0_SA_DQ<2>";
49"M_F_CPU0_SA_DQ<1>";
50"M_F_CPU0_SA_DQ<0>";
51"M_F_CPU0_SA_CB<7>";
52"M_F_CPU0_SA_CB<6>";
53"M_F_CPU0_SA_CB<5>";
54"M_F_CPU0_SA_CB<4>";
55"M_F_CPU0_SA_CB<3>";
56"M_F_CPU0_SA_CB<2>";
57"M_F_CPU0_SA_CB<1>";
58"M_F_CPU0_SA_CB<0>";
59"M_F_CPU0_SB_DQ<31>";
60"M_F_CPU0_SB_DQ<30>";
61"M_F_CPU0_SB_DQ<29>";
62"M_F_CPU0_SB_DQ<28>";
63"M_F_CPU0_SB_DQ<27>";
64"M_F_CPU0_SB_DQ<26>";
65"M_F_CPU0_SB_DQ<25>";
66"M_F_CPU0_SB_DQ<24>";
67"M_F_CPU0_SB_DQ<23>";
68"M_F_CPU0_SB_DQ<22>";
69"M_F_CPU0_SB_DQ<21>";
70"M_F_CPU0_SB_DQ<20>";
71"M_F_CPU0_SB_DQ<19>";
72"M_F_CPU0_SB_DQ<18>";
73"M_F_CPU0_SB_DQ<17>";
74"M_F_CPU0_SB_DQ<16>";
75"M_F_CPU0_SB_DQ<15>";
76"M_F_CPU0_SB_DQ<14>";
77"M_F_CPU0_SB_DQ<13>";
78"M_F_CPU0_SB_DQ<12>";
79"M_F_CPU0_SB_DQ<11>";
80"M_F_CPU0_SB_DQ<10>";
81"M_F_CPU0_SB_DQ<9>";
82"M_F_CPU0_SB_DQ<8>";
83"M_F_CPU0_SB_DQ<7>";
84"M_F_CPU0_SB_DQ<6>";
85"M_F_CPU0_SB_DQ<5>";
86"M_F_CPU0_SB_DQ<4>";
87"M_F_CPU0_SB_DQ<3>";
88"M_F_CPU0_SB_DQ<2>";
89"M_F_CPU0_SB_DQ<1>";
90"M_F_CPU0_SB_DQ<0>";
91"M_F_CPU0_SB_CB<7>";
92"M_F_CPU0_SB_CB<6>";
93"M_F_CPU0_SB_CB<5>";
94"M_F_CPU0_SB_CB<4>";
95"M_F_CPU0_SB_CB<3>";
96"M_F_CPU0_SB_CB<2>";
97"M_F_CPU0_SB_CB<1>";
98"M_F_CPU0_SB_CB<0>";
99"M_F_CPU0_SB_PAR";
100"M_F_CPU0_SB_DQS_DP<0>";
101"M_F_CPU0_SB_DQS_DP<1>";
102"M_F_CPU0_SB_DQS_DP<2>";
103"M_F_CPU0_SB_DQS_DP<3>";
104"M_F_CPU0_SB_DQS_DP<4>";
105"M_F_CPU0_SB_DQS_DP<5>";
106"M_F_CPU0_SB_DQS_DP<6>";
107"M_F_CPU0_SB_DQS_DP<7>";
108"M_F_CPU0_SB_DQS_DP<8>";
109"M_F_CPU0_SB_DQS_DP<9>";
110"M_F_CPU0_SB_DQS_DN<0>";
111"M_F_CPU0_SB_DQS_DN<1>";
112"M_F_CPU0_SB_DQS_DN<2>";
113"M_F_CPU0_SB_DQS_DN<3>";
114"M_F_CPU0_SB_DQS_DN<4>";
115"M_F_CPU0_SB_DQS_DN<5>";
116"M_F_CPU0_SB_DQS_DN<6>";
117"M_F_CPU0_SB_DQS_DN<7>";
118"M_F_CPU0_SB_DQS_DN<8>";
119"M_F_CPU0_SB_DQS_DN<9>";
120"M_F_CPU0_SB_CS_N<0>";
121"M_F_CPU0_SB_CS_N<1>";
122"M_F_CPU0_SB_CS_N<2>";
123"M_F_CPU0_SB_CS_N<3>";
124"M_F_CPU0_SB_CA<0>";
125"M_F_CPU0_SB_CA<1>";
126"M_F_CPU0_SB_CA<2>";
127"M_F_CPU0_SB_CA<3>";
128"M_F_CPU0_SB_CA<4>";
129"M_F_CPU0_SB_CA<5>";
130"M_F_CPU0_SB_CA<6>";
131"M_F_CPU0_SA_PAR";
132"M_F_CPU0_SA_DQS_DP<0>";
133"M_F_CPU0_SA_DQS_DP<1>";
134"M_F_CPU0_SA_DQS_DP<2>";
135"M_F_CPU0_SA_DQS_DP<3>";
136"M_F_CPU0_SA_DQS_DP<4>";
137"M_F_CPU0_SA_DQS_DP<5>";
138"M_F_CPU0_SA_DQS_DP<6>";
139"M_F_CPU0_SA_DQS_DP<7>";
140"M_F_CPU0_SA_DQS_DP<8>";
141"M_F_CPU0_SA_DQS_DP<9>";
142"M_F_CPU0_SA_DQS_DN<0>";
143"M_F_CPU0_SA_DQS_DN<1>";
144"M_F_CPU0_SA_DQS_DN<2>";
145"M_F_CPU0_SA_DQS_DN<3>";
146"M_F_CPU0_SA_DQS_DN<4>";
147"M_F_CPU0_SA_DQS_DN<5>";
148"M_F_CPU0_SA_DQS_DN<6>";
149"M_F_CPU0_SA_DQS_DN<7>";
150"M_F_CPU0_SA_DQS_DN<8>";
151"M_F_CPU0_SA_DQS_DN<9>";
152"M_F_CPU0_SA_CS_N<0>";
153"M_F_CPU0_SA_CS_N<1>";
154"M_F_CPU0_SA_CS_N<2>";
155"M_F_CPU0_SA_CS_N<3>";
156"M_F_CPU0_SA_CA<0>";
157"M_F_CPU0_SA_CA<1>";
158"M_F_CPU0_SA_CA<2>";
159"M_F_CPU0_SA_CA<3>";
160"M_F_CPU0_SA_CA<4>";
161"M_F_CPU0_SA_CA<5>";
162"M_F_CPU0_SA_CA<6>";
163"M_F_CPU0_SB_RSP<0>";
164"M_F_CPU0_SB_RSP<1>";
165"M_F_CPU0_SA_RSP<0>";
166"M_F_CPU0_SA_RSP<1>";
167"M_F_CPU0_ALERT_N";
%"TAP"
"1","(-225,-50)","2","standard","I10";
;
CDS_LIB"standard"
BODY_TYPE"PLUMBING"
HDL_TAP"TRUE";
"B \NAC \NWC"9;
"S \NAC"
BN"1"97;
%"TAP"
"1","(3200,450)","0","standard","I100";
;
CDS_LIB"standard"
BODY_TYPE"PLUMBING"
HDL_TAP"TRUE";
"B \NAC \NWC"2;
"S \NAC"
BN"1"153;
%"TAP"
"1","(3200,500)","0","standard","I101";
;
CDS_LIB"standard"
BODY_TYPE"PLUMBING"
HDL_TAP"TRUE";
"B \NAC \NWC"2;
"S \NAC"
BN"2"154;
%"TAP"
"1","(3200,550)","0","standard","I102";
;
CDS_LIB"standard"
BODY_TYPE"PLUMBING"
HDL_TAP"TRUE";
"B \NAC \NWC"2;
"S \NAC"
BN"3"155;
%"TAP"
"1","(3200,850)","0","standard","I103";
;
CDS_LIB"standard"
BODY_TYPE"PLUMBING"
HDL_TAP"TRUE";
"B \NAC \NWC"5;
"S \NAC"
BN"2"126;
%"TAP"
"1","(3200,750)","0","standard","I104";
;
CDS_LIB"standard"
BODY_TYPE"PLUMBING"
HDL_TAP"TRUE";
"B \NAC \NWC"5;
"S \NAC"
BN"0"124;
%"TAP"
"1","(3200,800)","0","standard","I105";
;
CDS_LIB"standard"
BODY_TYPE"PLUMBING"
HDL_TAP"TRUE";
"B \NAC \NWC"5;
"S \NAC"
BN"1"125;
%"TAP"
"1","(3200,950)","0","standard","I106";
;
CDS_LIB"standard"
BODY_TYPE"PLUMBING"
HDL_TAP"TRUE";
"B \NAC \NWC"5;
"S \NAC"
BN"4"128;
%"TAP"
"1","(3200,900)","0","standard","I107";
;
CDS_LIB"standard"
BODY_TYPE"PLUMBING"
HDL_TAP"TRUE";
"B \NAC \NWC"5;
"S \NAC"
BN"3"127;
%"TAP"
"1","(3200,1050)","0","standard","I108";
;
CDS_LIB"standard"
BODY_TYPE"PLUMBING"
HDL_TAP"TRUE";
"B \NAC \NWC"5;
"S \NAC"
BN"6"130;
%"TAP"
"1","(3200,1000)","0","standard","I109";
;
CDS_LIB"standard"
BODY_TYPE"PLUMBING"
HDL_TAP"TRUE";
"B \NAC \NWC"5;
"S \NAC"
BN"5"129;
%"TAP"
"1","(-225,-100)","2","standard","I11";
;
CDS_LIB"standard"
BODY_TYPE"PLUMBING"
HDL_TAP"TRUE";
"B \NAC \NWC"9;
"S \NAC"
BN"0"98;
%"TAP"
"1","(3200,1350)","0","standard","I110";
;
CDS_LIB"standard"
BODY_TYPE"PLUMBING"
HDL_TAP"TRUE";
"B \NAC \NWC"1;
"S \NAC"
BN"2"158;
%"TAP"
"1","(3200,1300)","0","standard","I111";
;
CDS_LIB"standard"
BODY_TYPE"PLUMBING"
HDL_TAP"TRUE";
"B \NAC \NWC"1;
"S \NAC"
BN"1"157;
%"TAP"
"1","(3200,1250)","0","standard","I112";
;
CDS_LIB"standard"
BODY_TYPE"PLUMBING"
HDL_TAP"TRUE";
"B \NAC \NWC"1;
"S \NAC"
BN"0"156;
%"TAP"
"1","(3200,1400)","0","standard","I113";
;
CDS_LIB"standard"
BODY_TYPE"PLUMBING"
HDL_TAP"TRUE";
"B \NAC \NWC"1;
"S \NAC"
BN"3"159;
%"TAP"
"1","(3200,1450)","0","standard","I114";
;
CDS_LIB"standard"
BODY_TYPE"PLUMBING"
HDL_TAP"TRUE";
"B \NAC \NWC"1;
"S \NAC"
BN"4"160;
%"TAP"
"1","(3200,1550)","0","standard","I115";
;
CDS_LIB"standard"
BODY_TYPE"PLUMBING"
HDL_TAP"TRUE";
"B \NAC \NWC"1;
"S \NAC"
BN"6"162;
%"TAP"
"1","(3200,1500)","0","standard","I116";
;
CDS_LIB"standard"
BODY_TYPE"PLUMBING"
HDL_TAP"TRUE";
"B \NAC \NWC"1;
"S \NAC"
BN"5"161;
%"TAP"
"1","(3200,1800)","0","standard","I117";
;
CDS_LIB"standard"
BODY_TYPE"PLUMBING"
HDL_TAP"TRUE";
"B \NAC \NWC"7;
"S \NAC"
BN"2"112;
%"TAP"
"1","(3200,1700)","0","standard","I118";
;
CDS_LIB"standard"
BODY_TYPE"PLUMBING"
HDL_TAP"TRUE";
"B \NAC \NWC"7;
"S \NAC"
BN"0"110;
%"TAP"
"1","(3200,1850)","0","standard","I119";
;
CDS_LIB"standard"
BODY_TYPE"PLUMBING"
HDL_TAP"TRUE";
"B \NAC \NWC"7;
"S \NAC"
BN"3"113;
%"TAP"
"1","(-225,50)","2","standard","I12";
;
CDS_LIB"standard"
BODY_TYPE"PLUMBING"
HDL_TAP"TRUE";
"B \NAC \NWC"9;
"S \NAC"
BN"3"95;
%"TAP"
"1","(3200,1750)","0","standard","I120";
;
CDS_LIB"standard"
BODY_TYPE"PLUMBING"
HDL_TAP"TRUE";
"B \NAC \NWC"7;
"S \NAC"
BN"1"111;
%"TAP"
"1","(3200,2150)","0","standard","I129";
;
CDS_LIB"standard"
BODY_TYPE"PLUMBING"
HDL_TAP"TRUE";
"B \NAC \NWC"7;
"S \NAC"
BN"9"119;
%"TAP"
"1","(-225,0)","2","standard","I13";
;
CDS_LIB"standard"
BODY_TYPE"PLUMBING"
HDL_TAP"TRUE";
"B \NAC \NWC"9;
"S \NAC"
BN"2"96;
%"TAP"
"1","(3200,2100)","0","standard","I130";
;
CDS_LIB"standard"
BODY_TYPE"PLUMBING"
HDL_TAP"TRUE";
"B \NAC \NWC"7;
"S \NAC"
BN"8"118;
%"TAP"
"1","(3200,2050)","0","standard","I131";
;
CDS_LIB"standard"
BODY_TYPE"PLUMBING"
HDL_TAP"TRUE";
"B \NAC \NWC"7;
"S \NAC"
BN"7"117;
%"TAP"
"1","(3200,2000)","0","standard","I132";
;
CDS_LIB"standard"
BODY_TYPE"PLUMBING"
HDL_TAP"TRUE";
"B \NAC \NWC"7;
"S \NAC"
BN"6"116;
%"TAP"
"1","(3200,1950)","0","standard","I133";
;
CDS_LIB"standard"
BODY_TYPE"PLUMBING"
HDL_TAP"TRUE";
"B \NAC \NWC"7;
"S \NAC"
BN"5"115;
%"TAP"
"1","(3200,1900)","0","standard","I134";
;
CDS_LIB"standard"
BODY_TYPE"PLUMBING"
HDL_TAP"TRUE";
"B \NAC \NWC"7;
"S \NAC"
BN"4"114;
%"TAP"
"1","(3200,2300)","0","standard","I135";
;
CDS_LIB"standard"
BODY_TYPE"PLUMBING"
HDL_TAP"TRUE";
"B \NAC \NWC"8;
"S \NAC"
BN"1"101;
%"TAP"
"1","(3200,2250)","0","standard","I136";
;
CDS_LIB"standard"
BODY_TYPE"PLUMBING"
HDL_TAP"TRUE";
"B \NAC \NWC"8;
"S \NAC"
BN"0"100;
%"TAP"
"1","(3200,2350)","0","standard","I137";
;
CDS_LIB"standard"
BODY_TYPE"PLUMBING"
HDL_TAP"TRUE";
"B \NAC \NWC"8;
"S \NAC"
BN"2"102;
%"TAP"
"1","(3200,2400)","0","standard","I138";
;
CDS_LIB"standard"
BODY_TYPE"PLUMBING"
HDL_TAP"TRUE";
"B \NAC \NWC"8;
"S \NAC"
BN"3"103;
%"TAP"
"1","(3200,2500)","0","standard","I139";
;
CDS_LIB"standard"
BODY_TYPE"PLUMBING"
HDL_TAP"TRUE";
"B \NAC \NWC"8;
"S \NAC"
BN"5"105;
%"TAP"
"1","(-225,100)","2","standard","I14";
;
CDS_LIB"standard"
BODY_TYPE"PLUMBING"
HDL_TAP"TRUE";
"B \NAC \NWC"9;
"S \NAC"
BN"4"94;
%"TAP"
"1","(3200,2450)","0","standard","I140";
;
CDS_LIB"standard"
BODY_TYPE"PLUMBING"
HDL_TAP"TRUE";
"B \NAC \NWC"8;
"S \NAC"
BN"4"104;
%"TAP"
"1","(3200,2550)","0","standard","I141";
;
CDS_LIB"standard"
BODY_TYPE"PLUMBING"
HDL_TAP"TRUE";
"B \NAC \NWC"8;
"S \NAC"
BN"6"106;
%"TAP"
"1","(3200,2600)","0","standard","I142";
;
CDS_LIB"standard"
BODY_TYPE"PLUMBING"
HDL_TAP"TRUE";
"B \NAC \NWC"8;
"S \NAC"
BN"7"107;
%"TAP"
"1","(3200,2650)","0","standard","I143";
;
CDS_LIB"standard"
BODY_TYPE"PLUMBING"
HDL_TAP"TRUE";
"B \NAC \NWC"8;
"S \NAC"
BN"8"108;
%"TAP"
"1","(3200,2900)","0","standard","I144";
;
CDS_LIB"standard"
BODY_TYPE"PLUMBING"
HDL_TAP"TRUE";
"B \NAC \NWC"3;
"S \NAC"
BN"1"143;
%"TAP"
"1","(3200,2850)","0","standard","I145";
;
CDS_LIB"standard"
BODY_TYPE"PLUMBING"
HDL_TAP"TRUE";
"B \NAC \NWC"3;
"S \NAC"
BN"0"142;
%"TAP"
"1","(3200,2700)","0","standard","I146";
;
CDS_LIB"standard"
BODY_TYPE"PLUMBING"
HDL_TAP"TRUE";
"B \NAC \NWC"8;
"S \NAC"
BN"9"109;
%"TAP"
"1","(3200,3000)","0","standard","I147";
;
CDS_LIB"standard"
BODY_TYPE"PLUMBING"
HDL_TAP"TRUE";
"B \NAC \NWC"3;
"S \NAC"
BN"3"145;
%"TAP"
"1","(3200,2950)","0","standard","I148";
;
CDS_LIB"standard"
BODY_TYPE"PLUMBING"
HDL_TAP"TRUE";
"B \NAC \NWC"3;
"S \NAC"
BN"2"144;
%"TAP"
"1","(3200,3050)","0","standard","I149";
;
CDS_LIB"standard"
BODY_TYPE"PLUMBING"
HDL_TAP"TRUE";
"B \NAC \NWC"3;
"S \NAC"
BN"4"146;
%"TAP"
"1","(-225,200)","2","standard","I15";
;
CDS_LIB"standard"
BODY_TYPE"PLUMBING"
HDL_TAP"TRUE";
"B \NAC \NWC"9;
"S \NAC"
BN"6"92;
%"TAP"
"1","(3200,3100)","0","standard","I150";
;
CDS_LIB"standard"
BODY_TYPE"PLUMBING"
HDL_TAP"TRUE";
"B \NAC \NWC"3;
"S \NAC"
BN"5"147;
%"TAP"
"1","(3200,3150)","0","standard","I151";
;
CDS_LIB"standard"
BODY_TYPE"PLUMBING"
HDL_TAP"TRUE";
"B \NAC \NWC"3;
"S \NAC"
BN"6"148;
%"TAP"
"1","(3200,3400)","0","standard","I152";
;
CDS_LIB"standard"
BODY_TYPE"PLUMBING"
HDL_TAP"TRUE";
"B \NAC \NWC"4;
"S \NAC"
BN"0"132;
%"TAP"
"1","(3200,3200)","0","standard","I153";
;
CDS_LIB"standard"
BODY_TYPE"PLUMBING"
HDL_TAP"TRUE";
"B \NAC \NWC"3;
"S \NAC"
BN"7"149;
%"TAP"
"1","(3200,3250)","0","standard","I154";
;
CDS_LIB"standard"
BODY_TYPE"PLUMBING"
HDL_TAP"TRUE";
"B \NAC \NWC"3;
"S \NAC"
BN"8"150;
%"TAP"
"1","(3200,3300)","0","standard","I155";
;
CDS_LIB"standard"
BODY_TYPE"PLUMBING"
HDL_TAP"TRUE";
"B \NAC \NWC"3;
"S \NAC"
BN"9"151;
%"TAP"
"1","(3200,3450)","0","standard","I156";
;
CDS_LIB"standard"
BODY_TYPE"PLUMBING"
HDL_TAP"TRUE";
"B \NAC \NWC"4;
"S \NAC"
BN"1"133;
%"TAP"
"1","(3200,3500)","0","standard","I157";
;
CDS_LIB"standard"
BODY_TYPE"PLUMBING"
HDL_TAP"TRUE";
"B \NAC \NWC"4;
"S \NAC"
BN"2"134;
%"TAP"
"1","(3200,3600)","0","standard","I158";
;
CDS_LIB"standard"
BODY_TYPE"PLUMBING"
HDL_TAP"TRUE";
"B \NAC \NWC"4;
"S \NAC"
BN"4"136;
%"TAP"
"1","(3200,3650)","0","standard","I159";
;
CDS_LIB"standard"
BODY_TYPE"PLUMBING"
HDL_TAP"TRUE";
"B \NAC \NWC"4;
"S \NAC"
BN"5"137;
%"TAP"
"1","(-225,150)","2","standard","I16";
;
CDS_LIB"standard"
BODY_TYPE"PLUMBING"
HDL_TAP"TRUE";
"B \NAC \NWC"9;
"S \NAC"
BN"5"93;
%"TAP"
"1","(3200,3550)","0","standard","I160";
;
CDS_LIB"standard"
BODY_TYPE"PLUMBING"
HDL_TAP"TRUE";
"B \NAC \NWC"4;
"S \NAC"
BN"3"135;
%"TAP"
"1","(3200,3700)","0","standard","I161";
;
CDS_LIB"standard"
BODY_TYPE"PLUMBING"
HDL_TAP"TRUE";
"B \NAC \NWC"4;
"S \NAC"
BN"6"138;
%"TAP"
"1","(3200,3750)","0","standard","I162";
;
CDS_LIB"standard"
BODY_TYPE"PLUMBING"
HDL_TAP"TRUE";
"B \NAC \NWC"4;
"S \NAC"
BN"7"139;
%"TAP"
"1","(3200,3850)","0","standard","I163";
;
CDS_LIB"standard"
BODY_TYPE"PLUMBING"
HDL_TAP"TRUE";
"B \NAC \NWC"4;
"S \NAC"
BN"9"141;
%"TAP"
"1","(3200,3800)","0","standard","I164";
;
CDS_LIB"standard"
BODY_TYPE"PLUMBING"
HDL_TAP"TRUE";
"B \NAC \NWC"4;
"S \NAC"
BN"8"140;
%"SOCKET4677_AZIF0045P001C01CS"
"13","(1500,1750)","0","pure_quanta","I169";
;
PART_NUMBER"DGA^7000023"
PART_TYPE"SMLF"
MATERIAL"IO"
VALUE"SOCKET4677_AZIF0045-P001C01CS"
$LOCATION"U2"
CDS_LIB"pure_quanta"
NEEDS_NO_SIZE"TRUE"
CDS_LMAN_SYM_OUTLINE"-1100,2250,1050,-2250"
CDS_LOCATION"U2"
$SEC"13"
CDS_SEC"13";
"DDR5_SB_PAR"
$PN"EJ39"99;
"DDR5_SB_ECC0"
$PN"ED32"98;
"DDR5_SB_ECC1"
$PN"EE31"97;
"DDR5_SB_ECC2"
$PN"EH32"96;
"DDR5_SB_ECC3"
$PN"EG31"95;
"DDR5_SB_ECC4"
$PN"EE35"94;
"DDR5_SB_ECC5"
$PN"ED34"93;
"DDR5_SB_ECC6"
$PN"EG35"92;
"DDR5_SB_ECC7"
$PN"EH34"91;
"DDR5_SB_DQS_DP0"
$PN"DT30"100;
"DDR5_SB_DQS_DP1"
$PN"EC21"101;
"DDR5_SB_DQS_DP2"
$PN"EK12"102;
"DDR5_SB_DQS_DP3"
$PN"DV18"103;
"DDR5_SB_DQS_DP4"
$PN"EG33"104;
"DDR5_SB_DQS_DP5"
$PN"DY30"105;
"DDR5_SB_DQS_DP6"
$PN"EG21"106;
"DDR5_SB_DQS_DP7"
$PN"EP12"107;
"DDR5_SB_DQS_DP8"
$PN"EB18"108;
"DDR5_SB_DQS_DP9"
$PN"EC33"109;
"DDR5_SB_DQS_DN0 \B"
$PN"DV30"110;
"DDR5_SB_DQS_DN1 \B"
$PN"EE21"111;
"DDR5_SB_DQS_DN2 \B"
$PN"EM12"112;
"DDR5_SB_DQS_DN3 \B"
$PN"DT18"113;
"DDR5_SB_DQS_DN4 \B"
$PN"EJ33"114;
"DDR5_SB_DQS_DN5 \B"
$PN"EB30"115;
"DDR5_SB_DQS_DN6 \B"
$PN"EJ21"116;
"DDR5_SB_DQS_DN7 \B"
$PN"ET12"117;
"DDR5_SB_DQS_DN8 \B"
$PN"DY18"118;
"DDR5_SB_DQS_DN9 \B"
$PN"EE33"119;
"DDR5_SB_DQ0"
$PN"DV32"90;
"DDR5_SB_DQ1"
$PN"DU31"89;
"DDR5_SB_DQ2"
$PN"DY32"88;
"DDR5_SB_DQ3"
$PN"EA31"87;
"DDR5_SB_DQ4"
$PN"DU29"86;
"DDR5_SB_DQ5"
$PN"DV28"85;
"DDR5_SB_DQ6"
$PN"EA29"84;
"DDR5_SB_DQ7"
$PN"DY28"83;
"DDR5_SB_DQ8"
$PN"EE23"82;
"DDR5_SB_DQ9"
$PN"ED22"81;
"DDR5_SB_DQ10"
$PN"EG23"80;
"DDR5_SB_DQ11"
$PN"EH22"79;
"DDR5_SB_DQ12"
$PN"ED20"78;
"DDR5_SB_DQ13"
$PN"EE19"77;
"DDR5_SB_DQ14"
$PN"EH20"76;
"DDR5_SB_DQ15"
$PN"EG19"75;
"DDR5_SB_DQ16"
$PN"EM14"74;
"DDR5_SB_DQ17"
$PN"EL13"73;
"DDR5_SB_DQ18"
$PN"EP14"72;
"DDR5_SB_DQ19"
$PN"ER13"71;
"DDR5_SB_DQ20"
$PN"EL11"70;
"DDR5_SB_DQ21"
$PN"EM10"69;
"DDR5_SB_DQ22"
$PN"ER11"68;
"DDR5_SB_DQ23"
$PN"EP10"67;
"DDR5_SB_DQ24"
$PN"DV20"66;
"DDR5_SB_DQ25"
$PN"DU19"65;
"DDR5_SB_DQ26"
$PN"DY20"64;
"DDR5_SB_DQ27"
$PN"EA19"63;
"DDR5_SB_DQ28"
$PN"EA17"62;
"DDR5_SB_DQ29"
$PN"DU17"61;
"DDR5_SB_DQ30"
$PN"EC17"60;
"DDR5_SB_DQ31"
$PN"DR17"59;
"DDR5_SB_CS_N0 \B"
$PN"EH38"120;
"DDR5_SB_CS_N1 \B"
$PN"EG37"121;
"DDR5_SB_CS_N2 \B"
$PN"ED38"122;
"DDR5_SB_CS_N3 \B"
$PN"EE37"123;
"DDR5_SB_CA0"
$PN"DV51"124;
"DDR5_SB_CA1"
$PN"DU50"125;
"DDR5_SB_CA2"
$PN"EE41"126;
"DDR5_SB_CA3"
$PN"EG41"127;
"DDR5_SB_CA4"
$PN"ED40"128;
"DDR5_SB_CA5"
$PN"EH40"129;
"DDR5_SB_CA6"
$PN"EC39"130;
"DDR5_SA_PAR"
$PN"EA50"131;
"DDR5_SA_ECC0"
$PN"EE60"58;
"DDR5_SA_ECC1"
$PN"ED59"57;
"DDR5_SA_ECC2"
$PN"EG60"56;
"DDR5_SA_ECC3"
$PN"EH59"55;
"DDR5_SA_ECC4"
$PN"ED57"54;
"DDR5_SA_ECC5"
$PN"EE56"53;
"DDR5_SA_ECC6"
$PN"EH57"52;
"DDR5_SA_ECC7"
$PN"EG56"51;
"DDR5_SA_DQS_DP0"
$PN"EC76"132;
"DDR5_SA_DQS_DP1"
$PN"DV67"133;
"DDR5_SA_DQS_DP2"
$PN"EE64"134;
"DDR5_SA_DQS_DP3"
$PN"DT55"135;
"DDR5_SA_DQS_DP4"
$PN"EC58"136;
"DDR5_SA_DQS_DP5"
$PN"EG76"137;
"DDR5_SA_DQS_DP6"
$PN"DY67"138;
"DDR5_SA_DQS_DP7"
$PN"EG64"139;
"DDR5_SA_DQS_DP8"
$PN"DY55"140;
"DDR5_SA_DQS_DP9"
$PN"EG58"141;
"DDR5_SA_DQS_DN0 \B"
$PN"EE76"142;
"DDR5_SA_DQS_DN1 \B"
$PN"DT67"143;
"DDR5_SA_DQS_DN2 \B"
$PN"EC64"144;
"DDR5_SA_DQS_DN3 \B"
$PN"DV55"145;
"DDR5_SA_DQS_DN4 \B"
$PN"EE58"146;
"DDR5_SA_DQS_DN5 \B"
$PN"EJ76"147;
"DDR5_SA_DQS_DN6 \B"
$PN"EB67"148;
"DDR5_SA_DQS_DN7 \B"
$PN"EJ64"149;
"DDR5_SA_DQS_DN8 \B"
$PN"EB55"150;
"DDR5_SA_DQS_DN9 \B"
$PN"EJ58"151;
"DDR5_SA_DQ0"
$PN"EB77"50;
"DDR5_SA_DQ1"
$PN"EH77"49;
"DDR5_SA_DQ2"
$PN"ED77"48;
"DDR5_SA_DQ3"
$PN"EG78"47;
"DDR5_SA_DQ4"
$PN"ED75"46;
"DDR5_SA_DQ5"
$PN"EE74"45;
"DDR5_SA_DQ6"
$PN"EH75"44;
"DDR5_SA_DQ7"
$PN"EG74"43;
"DDR5_SA_DQ8"
$PN"DV69"42;
"DDR5_SA_DQ9"
$PN"DU68"41;
"DDR5_SA_DQ10"
$PN"DY69"40;
"DDR5_SA_DQ11"
$PN"EA68"39;
"DDR5_SA_DQ12"
$PN"DU66"38;
"DDR5_SA_DQ13"
$PN"DV65"37;
"DDR5_SA_DQ14"
$PN"EA66"36;
"DDR5_SA_DQ15"
$PN"DY65"35;
"DDR5_SA_DQ16"
$PN"EE66"34;
"DDR5_SA_DQ17"
$PN"ED65"33;
"DDR5_SA_DQ18"
$PN"EG66"32;
"DDR5_SA_DQ19"
$PN"EH65"31;
"DDR5_SA_DQ20"
$PN"ED63"30;
"DDR5_SA_DQ21"
$PN"EE62"29;
"DDR5_SA_DQ22"
$PN"EH63"28;
"DDR5_SA_DQ23"
$PN"EG62"27;
"DDR5_SA_DQ24"
$PN"DV57"26;
"DDR5_SA_DQ25"
$PN"DU56"25;
"DDR5_SA_DQ26"
$PN"DY57"24;
"DDR5_SA_DQ27"
$PN"EA56"23;
"DDR5_SA_DQ28"
$PN"DU54"22;
"DDR5_SA_DQ29"
$PN"DV53"21;
"DDR5_SA_DQ30"
$PN"EA54"20;
"DDR5_SA_DQ31"
$PN"DY53"19;
"DDR5_SA_CS_N0 \B"
$PN"EG54"152;
"DDR5_SA_CS_N1 \B"
$PN"EH53"153;
"DDR5_SA_CS_N2 \B"
$PN"EE54"154;
"DDR5_SA_CS_N3 \B"
$PN"ED53"155;
"DDR5_SA_CA0"
$PN"EC52"156;
"DDR5_SA_CA1"
$PN"EJ52"157;
"DDR5_SA_CA2"
$PN"ED51"158;
"DDR5_SA_CA3"
$PN"EH51"159;
"DDR5_SA_CA4"
$PN"EE50"160;
"DDR5_SA_CA5"
$PN"EG50"161;
"DDR5_SA_CA6"
$PN"DY51"162;
"DDR5_CLK_DP0"
$PN"EB49"18;
"DDR5_CLK_DP1"
$PN"DT49"17;
"DDR5_CLK_DN0 \B"
$PN"DY49"16;
"DDR5_CLK_DN1 \B"
$PN"DV49"15;
"DDR5_B_RSP0"
$PN"DL48"163;
"DDR5_B_RSP1"
$PN"DK47"164;
"DDR5_A_RSP0"
$PN"DN48"165;
"DDR5_A_RSP1"
$PN"DP47"166;
"DDR5_ALERT_N \B"
$PN"CW48"167;
%"TAP"
"1","(-225,300)","2","standard","I17";
;
CDS_LIB"standard"
BODY_TYPE"PLUMBING"
HDL_TAP"TRUE";
"B \NAC \NWC"10;
"S \NAC"
BN"0"90;
%"TAP"
"1","(-225,250)","2","standard","I18";
;
CDS_LIB"standard"
BODY_TYPE"PLUMBING"
HDL_TAP"TRUE";
"B \NAC \NWC"9;
"S \NAC"
BN"7"91;
%"TAP"
"1","(-225,350)","2","standard","I19";
;
CDS_LIB"standard"
BODY_TYPE"PLUMBING"
HDL_TAP"TRUE";
"B \NAC \NWC"10;
"S \NAC"
BN"1"89;
%"TAP"
"1","(-225,450)","2","standard","I20";
;
CDS_LIB"standard"
BODY_TYPE"PLUMBING"
HDL_TAP"TRUE";
"B \NAC \NWC"10;
"S \NAC"
BN"3"87;
%"TAP"
"1","(-225,400)","2","standard","I21";
;
CDS_LIB"standard"
BODY_TYPE"PLUMBING"
HDL_TAP"TRUE";
"B \NAC \NWC"10;
"S \NAC"
BN"2"88;
%"TAP"
"1","(-225,500)","2","standard","I22";
;
CDS_LIB"standard"
BODY_TYPE"PLUMBING"
HDL_TAP"TRUE";
"B \NAC \NWC"10;
"S \NAC"
BN"4"86;
%"TAP"
"1","(-225,550)","2","standard","I23";
;
CDS_LIB"standard"
BODY_TYPE"PLUMBING"
HDL_TAP"TRUE";
"B \NAC \NWC"10;
"S \NAC"
BN"5"85;
%"TAP"
"1","(-225,600)","2","standard","I24";
;
CDS_LIB"standard"
BODY_TYPE"PLUMBING"
HDL_TAP"TRUE";
"B \NAC \NWC"10;
"S \NAC"
BN"6"84;
%"TAP"
"1","(-225,700)","2","standard","I25";
;
CDS_LIB"standard"
BODY_TYPE"PLUMBING"
HDL_TAP"TRUE";
"B \NAC \NWC"10;
"S \NAC"
BN"8"82;
%"TAP"
"1","(-225,650)","2","standard","I26";
;
CDS_LIB"standard"
BODY_TYPE"PLUMBING"
HDL_TAP"TRUE";
"B \NAC \NWC"10;
"S \NAC"
BN"7"83;
%"TAP"
"1","(-225,750)","2","standard","I27";
;
CDS_LIB"standard"
BODY_TYPE"PLUMBING"
HDL_TAP"TRUE";
"B \NAC \NWC"10;
"S \NAC"
BN"9"81;
%"TAP"
"1","(-225,800)","2","standard","I28";
;
CDS_LIB"standard"
BODY_TYPE"PLUMBING"
HDL_TAP"TRUE";
"B \NAC \NWC"10;
"S \NAC"
BN"10"80;
%"TAP"
"1","(-225,850)","2","standard","I29";
;
CDS_LIB"standard"
BODY_TYPE"PLUMBING"
HDL_TAP"TRUE";
"B \NAC \NWC"10;
"S \NAC"
BN"11"79;
%"TAP"
"1","(-225,-300)","2","standard","I3";
;
CDS_LIB"standard"
BODY_TYPE"PLUMBING"
HDL_TAP"TRUE";
"B \NAC \NWC"14;
"S \NAC"
BN"1"15;
%"TAP"
"1","(-225,950)","2","standard","I30";
;
CDS_LIB"standard"
BODY_TYPE"PLUMBING"
HDL_TAP"TRUE";
"B \NAC \NWC"10;
"S \NAC"
BN"13"77;
%"TAP"
"1","(-225,900)","2","standard","I31";
;
CDS_LIB"standard"
BODY_TYPE"PLUMBING"
HDL_TAP"TRUE";
"B \NAC \NWC"10;
"S \NAC"
BN"12"78;
%"TAP"
"1","(-225,1000)","2","standard","I32";
;
CDS_LIB"standard"
BODY_TYPE"PLUMBING"
HDL_TAP"TRUE";
"B \NAC \NWC"10;
"S \NAC"
BN"14"76;
%"TAP"
"1","(-225,1100)","2","standard","I33";
;
CDS_LIB"standard"
BODY_TYPE"PLUMBING"
HDL_TAP"TRUE";
"B \NAC \NWC"10;
"S \NAC"
BN"16"74;
%"TAP"
"1","(-225,1050)","2","standard","I34";
;
CDS_LIB"standard"
BODY_TYPE"PLUMBING"
HDL_TAP"TRUE";
"B \NAC \NWC"10;
"S \NAC"
BN"15"75;
%"TAP"
"1","(-225,1150)","2","standard","I35";
;
CDS_LIB"standard"
BODY_TYPE"PLUMBING"
HDL_TAP"TRUE";
"B \NAC \NWC"10;
"S \NAC"
BN"17"73;
%"TAP"
"1","(-225,1200)","2","standard","I36";
;
CDS_LIB"standard"
BODY_TYPE"PLUMBING"
HDL_TAP"TRUE";
"B \NAC \NWC"10;
"S \NAC"
BN"18"72;
%"TAP"
"1","(-225,1250)","2","standard","I37";
;
CDS_LIB"standard"
BODY_TYPE"PLUMBING"
HDL_TAP"TRUE";
"B \NAC \NWC"10;
"S \NAC"
BN"19"71;
%"TAP"
"1","(-225,1350)","2","standard","I38";
;
CDS_LIB"standard"
BODY_TYPE"PLUMBING"
HDL_TAP"TRUE";
"B \NAC \NWC"10;
"S \NAC"
BN"21"69;
%"TAP"
"1","(-225,1300)","2","standard","I39";
;
CDS_LIB"standard"
BODY_TYPE"PLUMBING"
HDL_TAP"TRUE";
"B \NAC \NWC"10;
"S \NAC"
BN"20"70;
%"TAP"
"1","(-225,-350)","2","standard","I4";
;
CDS_LIB"standard"
BODY_TYPE"PLUMBING"
HDL_TAP"TRUE";
"B \NAC \NWC"14;
"S \NAC"
BN"0"16;
%"TAP"
"1","(-225,1400)","2","standard","I40";
;
CDS_LIB"standard"
BODY_TYPE"PLUMBING"
HDL_TAP"TRUE";
"B \NAC \NWC"10;
"S \NAC"
BN"22"68;
%"TAP"
"1","(-225,1450)","2","standard","I41";
;
CDS_LIB"standard"
BODY_TYPE"PLUMBING"
HDL_TAP"TRUE";
"B \NAC \NWC"10;
"S \NAC"
BN"23"67;
%"TAP"
"1","(-225,1500)","2","standard","I42";
;
CDS_LIB"standard"
BODY_TYPE"PLUMBING"
HDL_TAP"TRUE";
"B \NAC \NWC"10;
"S \NAC"
BN"24"66;
%"TAP"
"1","(-225,1600)","2","standard","I43";
;
CDS_LIB"standard"
BODY_TYPE"PLUMBING"
HDL_TAP"TRUE";
"B \NAC \NWC"10;
"S \NAC"
BN"26"64;
%"TAP"
"1","(-225,1550)","2","standard","I44";
;
CDS_LIB"standard"
BODY_TYPE"PLUMBING"
HDL_TAP"TRUE";
"B \NAC \NWC"10;
"S \NAC"
BN"25"65;
%"TAP"
"1","(-225,1650)","2","standard","I45";
;
CDS_LIB"standard"
BODY_TYPE"PLUMBING"
HDL_TAP"TRUE";
"B \NAC \NWC"10;
"S \NAC"
BN"27"63;
%"TAP"
"1","(-225,1700)","2","standard","I46";
;
CDS_LIB"standard"
BODY_TYPE"PLUMBING"
HDL_TAP"TRUE";
"B \NAC \NWC"10;
"S \NAC"
BN"28"62;
%"TAP"
"1","(-225,1750)","2","standard","I47";
;
CDS_LIB"standard"
BODY_TYPE"PLUMBING"
HDL_TAP"TRUE";
"B \NAC \NWC"10;
"S \NAC"
BN"29"61;
%"TAP"
"1","(-225,1850)","2","standard","I48";
;
CDS_LIB"standard"
BODY_TYPE"PLUMBING"
HDL_TAP"TRUE";
"B \NAC \NWC"10;
"S \NAC"
BN"31"59;
%"TAP"
"1","(-225,1800)","2","standard","I49";
;
CDS_LIB"standard"
BODY_TYPE"PLUMBING"
HDL_TAP"TRUE";
"B \NAC \NWC"10;
"S \NAC"
BN"30"60;
%"TAP"
"1","(-225,-250)","2","standard","I5";
;
CDS_LIB"standard"
BODY_TYPE"PLUMBING"
HDL_TAP"TRUE";
"B \NAC \NWC"13;
"S \NAC"
BN"0"18;
%"TAP"
"1","(-225,2000)","2","standard","I52";
;
CDS_LIB"standard"
BODY_TYPE"PLUMBING"
HDL_TAP"TRUE";
"B \NAC \NWC"11;
"S \NAC"
BN"2"56;
%"TAP"
"1","(-225,1900)","2","standard","I53";
;
CDS_LIB"standard"
BODY_TYPE"PLUMBING"
HDL_TAP"TRUE";
"B \NAC \NWC"11;
"S \NAC"
BN"0"58;
%"TAP"
"1","(-225,1950)","2","standard","I54";
;
CDS_LIB"standard"
BODY_TYPE"PLUMBING"
HDL_TAP"TRUE";
"B \NAC \NWC"11;
"S \NAC"
BN"1"57;
%"TAP"
"1","(-225,2050)","2","standard","I55";
;
CDS_LIB"standard"
BODY_TYPE"PLUMBING"
HDL_TAP"TRUE";
"B \NAC \NWC"11;
"S \NAC"
BN"3"55;
%"TAP"
"1","(-225,2100)","2","standard","I56";
;
CDS_LIB"standard"
BODY_TYPE"PLUMBING"
HDL_TAP"TRUE";
"B \NAC \NWC"11;
"S \NAC"
BN"4"54;
%"TAP"
"1","(-225,2150)","2","standard","I57";
;
CDS_LIB"standard"
BODY_TYPE"PLUMBING"
HDL_TAP"TRUE";
"B \NAC \NWC"11;
"S \NAC"
BN"5"53;
%"TAP"
"1","(-225,2250)","2","standard","I58";
;
CDS_LIB"standard"
BODY_TYPE"PLUMBING"
HDL_TAP"TRUE";
"B \NAC \NWC"11;
"S \NAC"
BN"7"51;
%"TAP"
"1","(-225,2200)","2","standard","I59";
;
CDS_LIB"standard"
BODY_TYPE"PLUMBING"
HDL_TAP"TRUE";
"B \NAC \NWC"11;
"S \NAC"
BN"6"52;
%"TAP"
"1","(-225,-200)","2","standard","I6";
;
CDS_LIB"standard"
BODY_TYPE"PLUMBING"
HDL_TAP"TRUE";
"B \NAC \NWC"13;
"S \NAC"
BN"1"17;
%"TAP"
"1","(-225,2350)","2","standard","I60";
;
CDS_LIB"standard"
BODY_TYPE"PLUMBING"
HDL_TAP"TRUE";
"B \NAC \NWC"12;
"S \NAC"
BN"1"49;
%"TAP"
"1","(-225,2300)","2","standard","I61";
;
CDS_LIB"standard"
BODY_TYPE"PLUMBING"
HDL_TAP"TRUE";
"B \NAC \NWC"12;
"S \NAC"
BN"0"50;
%"TAP"
"1","(-225,2400)","2","standard","I62";
;
CDS_LIB"standard"
BODY_TYPE"PLUMBING"
HDL_TAP"TRUE";
"B \NAC \NWC"12;
"S \NAC"
BN"2"48;
%"TAP"
"1","(-225,2500)","2","standard","I63";
;
CDS_LIB"standard"
BODY_TYPE"PLUMBING"
HDL_TAP"TRUE";
"B \NAC \NWC"12;
"S \NAC"
BN"4"46;
%"TAP"
"1","(-225,2450)","2","standard","I64";
;
CDS_LIB"standard"
BODY_TYPE"PLUMBING"
HDL_TAP"TRUE";
"B \NAC \NWC"12;
"S \NAC"
BN"3"47;
%"TAP"
"1","(-225,2550)","2","standard","I65";
;
CDS_LIB"standard"
BODY_TYPE"PLUMBING"
HDL_TAP"TRUE";
"B \NAC \NWC"12;
"S \NAC"
BN"5"45;
%"TAP"
"1","(-225,2600)","2","standard","I66";
;
CDS_LIB"standard"
BODY_TYPE"PLUMBING"
HDL_TAP"TRUE";
"B \NAC \NWC"12;
"S \NAC"
BN"6"44;
%"TAP"
"1","(-225,2650)","2","standard","I67";
;
CDS_LIB"standard"
BODY_TYPE"PLUMBING"
HDL_TAP"TRUE";
"B \NAC \NWC"12;
"S \NAC"
BN"7"43;
%"TAP"
"1","(-225,2750)","2","standard","I68";
;
CDS_LIB"standard"
BODY_TYPE"PLUMBING"
HDL_TAP"TRUE";
"B \NAC \NWC"12;
"S \NAC"
BN"9"41;
%"TAP"
"1","(-225,2700)","2","standard","I69";
;
CDS_LIB"standard"
BODY_TYPE"PLUMBING"
HDL_TAP"TRUE";
"B \NAC \NWC"12;
"S \NAC"
BN"8"42;
%"TAP"
"1","(-225,2800)","2","standard","I70";
;
CDS_LIB"standard"
BODY_TYPE"PLUMBING"
HDL_TAP"TRUE";
"B \NAC \NWC"12;
"S \NAC"
BN"10"40;
%"TAP"
"1","(-225,2850)","2","standard","I71";
;
CDS_LIB"standard"
BODY_TYPE"PLUMBING"
HDL_TAP"TRUE";
"B \NAC \NWC"12;
"S \NAC"
BN"11"39;
%"TAP"
"1","(-225,2900)","2","standard","I72";
;
CDS_LIB"standard"
BODY_TYPE"PLUMBING"
HDL_TAP"TRUE";
"B \NAC \NWC"12;
"S \NAC"
BN"12"38;
%"TAP"
"1","(-225,3000)","2","standard","I73";
;
CDS_LIB"standard"
BODY_TYPE"PLUMBING"
HDL_TAP"TRUE";
"B \NAC \NWC"12;
"S \NAC"
BN"14"36;
%"TAP"
"1","(-225,2950)","2","standard","I74";
;
CDS_LIB"standard"
BODY_TYPE"PLUMBING"
HDL_TAP"TRUE";
"B \NAC \NWC"12;
"S \NAC"
BN"13"37;
%"TAP"
"1","(-225,3050)","2","standard","I75";
;
CDS_LIB"standard"
BODY_TYPE"PLUMBING"
HDL_TAP"TRUE";
"B \NAC \NWC"12;
"S \NAC"
BN"15"35;
%"TAP"
"1","(-225,3150)","2","standard","I76";
;
CDS_LIB"standard"
BODY_TYPE"PLUMBING"
HDL_TAP"TRUE";
"B \NAC \NWC"12;
"S \NAC"
BN"17"33;
%"TAP"
"1","(-225,3100)","2","standard","I77";
;
CDS_LIB"standard"
BODY_TYPE"PLUMBING"
HDL_TAP"TRUE";
"B \NAC \NWC"12;
"S \NAC"
BN"16"34;
%"TAP"
"1","(-225,3200)","2","standard","I78";
;
CDS_LIB"standard"
BODY_TYPE"PLUMBING"
HDL_TAP"TRUE";
"B \NAC \NWC"12;
"S \NAC"
BN"18"32;
%"TAP"
"1","(-225,3250)","2","standard","I79";
;
CDS_LIB"standard"
BODY_TYPE"PLUMBING"
HDL_TAP"TRUE";
"B \NAC \NWC"12;
"S \NAC"
BN"19"31;
%"TAP"
"1","(-225,3300)","2","standard","I80";
;
CDS_LIB"standard"
BODY_TYPE"PLUMBING"
HDL_TAP"TRUE";
"B \NAC \NWC"12;
"S \NAC"
BN"20"30;
%"TAP"
"1","(-225,3400)","2","standard","I81";
;
CDS_LIB"standard"
BODY_TYPE"PLUMBING"
HDL_TAP"TRUE";
"B \NAC \NWC"12;
"S \NAC"
BN"22"28;
%"TAP"
"1","(-225,3350)","2","standard","I82";
;
CDS_LIB"standard"
BODY_TYPE"PLUMBING"
HDL_TAP"TRUE";
"B \NAC \NWC"12;
"S \NAC"
BN"21"29;
%"TAP"
"1","(-225,3500)","2","standard","I83";
;
CDS_LIB"standard"
BODY_TYPE"PLUMBING"
HDL_TAP"TRUE";
"B \NAC \NWC"12;
"S \NAC"
BN"24"26;
%"TAP"
"1","(-225,3450)","2","standard","I84";
;
CDS_LIB"standard"
BODY_TYPE"PLUMBING"
HDL_TAP"TRUE";
"B \NAC \NWC"12;
"S \NAC"
BN"23"27;
%"TAP"
"1","(-225,3550)","2","standard","I85";
;
CDS_LIB"standard"
BODY_TYPE"PLUMBING"
HDL_TAP"TRUE";
"B \NAC \NWC"12;
"S \NAC"
BN"25"25;
%"TAP"
"1","(-225,3650)","2","standard","I86";
;
CDS_LIB"standard"
BODY_TYPE"PLUMBING"
HDL_TAP"TRUE";
"B \NAC \NWC"12;
"S \NAC"
BN"27"23;
%"TAP"
"1","(-225,3600)","2","standard","I87";
;
CDS_LIB"standard"
BODY_TYPE"PLUMBING"
HDL_TAP"TRUE";
"B \NAC \NWC"12;
"S \NAC"
BN"26"24;
%"TAP"
"1","(-225,3700)","2","standard","I88";
;
CDS_LIB"standard"
BODY_TYPE"PLUMBING"
HDL_TAP"TRUE";
"B \NAC \NWC"12;
"S \NAC"
BN"28"22;
%"TAP"
"1","(-225,3750)","2","standard","I89";
;
CDS_LIB"standard"
BODY_TYPE"PLUMBING"
HDL_TAP"TRUE";
"B \NAC \NWC"12;
"S \NAC"
BN"29"21;
%"TAP"
"1","(-225,3800)","2","standard","I90";
;
CDS_LIB"standard"
BODY_TYPE"PLUMBING"
HDL_TAP"TRUE";
"B \NAC \NWC"12;
"S \NAC"
BN"30"20;
%"TAP"
"1","(-225,3850)","2","standard","I91";
;
CDS_LIB"standard"
BODY_TYPE"PLUMBING"
HDL_TAP"TRUE";
"B \NAC \NWC"12;
"S \NAC"
BN"31"19;
%"TAP"
"1","(3200,100)","0","standard","I95";
;
CDS_LIB"standard"
BODY_TYPE"PLUMBING"
HDL_TAP"TRUE";
"B \NAC \NWC"6;
"S \NAC"
BN"0"120;
%"TAP"
"1","(3200,200)","0","standard","I96";
;
CDS_LIB"standard"
BODY_TYPE"PLUMBING"
HDL_TAP"TRUE";
"B \NAC \NWC"6;
"S \NAC"
BN"2"122;
%"TAP"
"1","(3200,150)","0","standard","I97";
;
CDS_LIB"standard"
BODY_TYPE"PLUMBING"
HDL_TAP"TRUE";
"B \NAC \NWC"6;
"S \NAC"
BN"1"121;
%"TAP"
"1","(3200,250)","0","standard","I98";
;
CDS_LIB"standard"
BODY_TYPE"PLUMBING"
HDL_TAP"TRUE";
"B \NAC \NWC"6;
"S \NAC"
BN"3"123;
%"TAP"
"1","(3200,400)","0","standard","I99";
;
CDS_LIB"standard"
BODY_TYPE"PLUMBING"
HDL_TAP"TRUE";
"B \NAC \NWC"2;
"S \NAC"
BN"0"152;
END.
